(lib_symbols
	(symbol "si-simulation-test-board:Antenna" 
            (pin_numbers hide) 
            (pin_names 
                (offset 1.016) hide) 
            (in_bom yes) 
            (on_board yes) 
            (property "Reference" "AE" 
                (id 0) 
                (at -1.905 1.905 0) 
                (effects 
                    (font 
                        (size 1.27 1.27)) 
                    (justify right))) 
            (property "Value" "Antenna" 
                (id 1) 
                (at -1.905 0 0) 
                (effects 
                    (font 
                        (size 1.27 1.27)) 
                    (justify right))) 
            (property "Footprint" "" 
                (id 2) 
                (at 0 0 0) 
                (effects 
                    (font 
                        (size 1.27 1.27)) hide)) 
            (property "Datasheet" "~" 
                (id 3) 
                (at 0 0 0) 
                (effects 
                    (font 
                        (size 1.27 1.27)) hide)) 
            (property "ki_keywords" "antenna" 
                (id 4) 
                (at 0 0 0) 
                (effects 
                    (font 
                        (size 1.27 1.27)) hide)) 
            (property "ki_description" "Antenna" 
                (id 5) 
                (at 0 0 0) 
                (effects 
                    (font 
                        (size 1.27 1.27)) hide)) 
            (symbol "Antenna_0_1" 
                (polyline 
                    (pts 
                        (xy 0 2.54) 
                        (xy 0 -3.81)) 
                    (stroke 
                        (width 0.254) 
                        (type default) 
                        (color 0 0 0 0)) 
                    (fill 
                        (type none))) 
                (polyline 
                    (pts 
                        (xy 1.27 2.54) 
                        (xy 0 -2.54) 
                        (xy -1.27 2.54)) 
                    (stroke 
                        (width 0.254) 
                        (type default) 
                        (color 0 0 0 0)) 
                    (fill 
                        (type none)))) 
            (symbol "Antenna_1_1" 
                (pin input line 
                    (at 0 -5.08 90) 
                    (length 2.54) 
                    (name "A" 
                        (effects 
                            (font 
                                (size 1.27 1.27)))) 
                    (number "1" 
                        (effects 
                            (font 
                                (size 1.27 1.27)))))))
	(symbol "si-simulation-test-board:C_100n_0402" 
            (pin_numbers hide) 
            (pin_names hide) 
            (in_bom yes) 
            (on_board yes) 
            (property "Reference" "C" 
                (id 0) 
                (at 20.32 -5.08 0) 
                (effects 
                    (font 
                        (size 1.27 1.27) 
                        (thickness 0.15)) 
                    (justify left bottom))) 
            (property "Value" "C_100n_0402" 
                (id 1) 
                (at 20.32 -10.16 0) 
                (effects 
                    (font 
                        (size 1.27 1.27) 
                        (thickness 0.15)) 
                    (justify left bottom) hide)) 
            (property "Footprint" "si-simulation-test-board-footprints:C_0402_1005Metric" 
                (id 2) 
                (at 20.32 -12.7 0) 
                (effects 
                    (font 
                        (size 1.27 1.27) 
                        (thickness 0.15)) 
                    (justify left bottom) hide)) 
            (property "Datasheet" "https://search.murata.co.jp/Ceramy/image/img/A01X/G101/ENG/GRM155R61H104KE14-01.pdf" 
                (id 3) 
                (at 20.32 -15.24 0) 
                (effects 
                    (font 
                        (size 1.27 1.27) 
                        (thickness 0.15)) 
                    (justify left bottom) hide)) 
            (property "MPN" "GRM155R61H104KE14D" 
                (id 4) 
                (at 20.32 -17.78 0) 
                (effects 
                    (font 
                        (size 1.27 1.27) 
                        (thickness 0.15)) 
                    (justify left bottom) hide)) 
            (property "Manufacturer" "Murata" 
                (id 5) 
                (at 20.32 -20.32 0) 
                (effects 
                    (font 
                        (size 1.27 1.27) 
                        (thickness 0.15)) 
                    (justify left bottom) hide)) 
            (property "License" "Apache-2.0" 
                (id 6) 
                (at 20.32 -22.86 0) 
                (effects 
                    (font 
                        (size 1.27 1.27) 
                        (thickness 0.15)) 
                    (justify left bottom) hide)) 
            (property "Author" "Antmicro" 
                (id 7) 
                (at 20.32 -25.4 0) 
                (effects 
                    (font 
                        (size 1.27 1.27) 
                        (thickness 0.15)) 
                    (justify left bottom) hide)) 
            (property "Val" "100n" 
                (id 8) 
                (at 20.32 -7.62 0) 
                (effects 
                    (font 
                        (size 1.27 1.27) 
                        (thickness 0.15)) 
                    (justify left bottom))) 
            (property "Voltage" "50V" 
                (id 9) 
                (at 20.32 -27.94 0) 
                (effects 
                    (font 
                        (size 1.27 1.27)) 
                    (justify left bottom) hide)) 
            (property "Dielectric" "X5R" 
                (id 10) 
                (at 20.32 -30.48 0) 
                (effects 
                    (font 
                        (size 1.27 1.27)) 
                    (justify left bottom) hide)) 
            (property "ki_description" "SMD Multilayer Ceramic Capacitor, 0.1 µF, 50 V, 0402 [1005 Metric], ± 10%, X5R, GRM Series" 
                (id 11) 
                (at 0 0 0) 
                (effects 
                    (font 
                        (size 1.27 1.27)) hide)) 
            (symbol "C_100n_0402_0_1" 
                (polyline 
                    (pts 
                        (xy 2.032 -1.524) 
                        (xy 2.032 1.524)) 
                    (stroke 
                        (width 0.3048) 
                        (type default) 
                        (color 0 0 0 0)) 
                    (fill 
                        (type none))) 
                (polyline 
                    (pts 
                        (xy 3.048 -1.524) 
                        (xy 3.048 1.524)) 
                    (stroke 
                        (width 0.3302) 
                        (type default) 
                        (color 0 0 0 0)) 
                    (fill 
                        (type none)))) 
            (symbol "C_100n_0402_1_1" 
                (pin passive line 
                    (at 0 0 0) 
                    (length 2.032) 
                    (name "~" 
                        (effects 
                            (font 
                                (size 1.27 1.27)))) 
                    (number "1" 
                        (effects 
                            (font 
                                (size 1.27 1.27))))) 
                (pin passive line 
                    (at 5.08 0 180) 
                    (length 2.032) 
                    (name "~" 
                        (effects 
                            (font 
                                (size 1.27 1.27)))) 
                    (number "2" 
                        (effects 
                            (font 
                                (size 1.27 1.27)))))))
	(symbol "si-simulation-test-board:Conn_SMA_RF2-143-T-17-50-G" 
            (pin_names hide) 
            (in_bom yes) 
            (on_board yes) 
            (property "Reference" "J" 
                (id 0) 
                (at 20.32 -5.08 0) 
                (effects 
                    (font 
                        (size 1.27 1.27) 
                        (thickness 0.15)) 
                    (justify left bottom))) 
            (property "Value" "Conn_SMA_RF2-143-T-17-50-G" 
                (id 1) 
                (at 20.32 -7.62 0) 
                (effects 
                    (font 
                        (size 1.27 1.27) 
                        (thickness 0.15)) 
                    (justify left bottom))) 
            (property "Footprint" "si-simulation-test-board-footprints:RF_SMA_BoardEdge_RF2-143-T-17-50-G" 
                (id 2) 
                (at 20.32 -10.16 0) 
                (effects 
                    (font 
                        (size 1.27 1.27) 
                        (thickness 0.15)) 
                    (justify left bottom) hide)) 
            (property "Datasheet" "https://www.tme.eu/Document/613028b507cfc72671e78c1d2ad14b1d/RF2-154-T-17-50-G.pdf" 
                (id 3) 
                (at 20.32 -12.7 0) 
                (effects 
                    (font 
                        (size 1.27 1.27) 
                        (thickness 0.15)) 
                    (justify left bottom) hide)) 
            (property "MPN" "RF2-143-T-17-50-G" 
                (id 4) 
                (at 20.32 -15.24 0) 
                (effects 
                    (font 
                        (size 1.27 1.27) 
                        (thickness 0.15)) 
                    (justify left bottom) hide)) 
            (property "Manufacturer" "ADAM TECH" 
                (id 5) 
                (at 20.32 -17.78 0) 
                (effects 
                    (font 
                        (size 1.27 1.27) 
                        (thickness 0.15)) 
                    (justify left bottom) hide)) 
            (property "Author" "Antmicro" 
                (id 6) 
                (at 20.32 -20.32 0) 
                (effects 
                    (font 
                        (size 1.27 1.27) 
                        (thickness 0.15)) 
                    (justify left bottom) hide)) 
            (property "License" "Apache-2.0" 
                (id 7) 
                (at 20.32 -22.86 0) 
                (effects 
                    (font 
                        (size 1.27 1.27) 
                        (thickness 0.15)) 
                    (justify left bottom) hide)) 
            (property "ki_description" "RF / Coaxial Connector, SMA, 50Ω " 
                (id 8) 
                (at 0 0 0) 
                (effects 
                    (font 
                        (size 1.27 1.27)) hide)) 
            (property "ki_fp_filters" "*BNC* *SMA* *SMB* *SMC* *Cinch*" 
                (id 9) 
                (at 0 0 0) 
                (effects 
                    (font 
                        (size 1.27 1.27)) hide)) 
            (symbol "Conn_SMA_RF2-143-T-17-50-G_1_1" 
                (polyline 
                    (pts 
                        (xy 2.54 0) 
                        (xy 4.572 0)) 
                    (stroke 
                        (width 0.254) 
                        (type default) 
                        (color 0 0 0 0)) 
                    (fill 
                        (type none))) 
                (polyline 
                    (pts 
                        (xy 5.08 -2.54) 
                        (xy 5.08 -1.778)) 
                    (stroke 
                        (width 0.254) 
                        (type default) 
                        (color 0 0 0 0)) 
                    (fill 
                        (type none))) 
                (arc 
                    (start 3.302 -0.508) 
                    (mid 5.302 -1.808) 
                    (end 6.858 0) 
                    (stroke 
                        (width 0.254) 
                        (type default) 
                        (color 0 0 0 0)) 
                    (fill 
                        (type none))) 
                (circle 
                    (center 5.08 0) 
                    (radius 0.508) 
                    (stroke 
                        (width 0.254) 
                        (type default) 
                        (color 0 0 0 0)) 
                    (fill 
                        (type none))) 
                (arc 
                    (start 6.858 0) 
                    (mid 5.302 1.8083) 
                    (end 3.302 0.508) 
                    (stroke 
                        (width 0.254) 
                        (type default) 
                        (color 0 0 0 0)) 
                    (fill 
                        (type none))) 
                (pin passive line 
                    (at 0 0 0) 
                    (length 2.54) 
                    (name "1" 
                        (effects 
                            (font 
                                (size 1.27 1.27)))) 
                    (number "1" 
                        (effects 
                            (font 
                                (size 1.27 1.27))))) 
                (pin passive line 
                    (at 5.08 -5.08 90) 
                    (length 2.54) 
                    (name "2" 
                        (effects 
                            (font 
                                (size 1.27 1.27)))) 
                    (number "2" 
                        (effects 
                            (font 
                                (size 1.27 1.27)))))))
	(symbol "si-simulation-test-board:GND" 
            (power) 
            (pin_numbers hide) 
            (pin_names hide) 
            (in_bom yes) 
            (on_board yes) 
            (property "Reference" "#PWR" 
                (id 0) 
                (at 8.89 -2.54 0) 
                (effects 
                    (font 
                        (size 1.27 1.27) 
                        (thickness 0.15)) 
                    (justify left bottom) hide)) 
            (property "Value" "GND" 
                (id 1) 
                (at 8.89 -5.08 0) 
                (effects 
                    (font 
                        (size 1.27 1.27) 
                        (thickness 0.15)) 
                    (justify left bottom))) 
            (property "Footprint" "" 
                (id 2) 
                (at 8.89 -7.62 0) 
                (effects 
                    (font 
                        (size 1.27 1.27) 
                        (thickness 0.15)) 
                    (justify left bottom) hide)) 
            (property "Datasheet" "" 
                (id 3) 
                (at 8.89 -12.7 0) 
                (effects 
                    (font 
                        (size 1.27 1.27) 
                        (thickness 0.15)) 
                    (justify left bottom) hide)) 
            (property "Author" "Antmicro" 
                (id 4) 
                (at 8.89 -7.62 0) 
                (effects 
                    (font 
                        (size 1.27 1.27) 
                        (thickness 0.15)) 
                    (justify left bottom) hide)) 
            (property "License" "Apache-2.0" 
                (id 5) 
                (at 8.89 -10.16 0) 
                (effects 
                    (font 
                        (size 1.27 1.27) 
                        (thickness 0.15)) 
                    (justify left bottom) hide)) 
            (symbol "GND_1_1" 
                (polyline 
                    (pts 
                        (xy 0 0) 
                        (xy 0 -1.27) 
                        (xy 1.27 -1.27) 
                        (xy 0 -2.54) 
                        (xy -1.27 -1.27) 
                        (xy 0 -1.27)) 
                    (stroke 
                        (width 0) 
                        (type default) 
                        (color 0 0 0 0)) 
                    (fill 
                        (type none))) 
                (pin power_in line 
                    (at 0 0 270) 
                    (length 0) 
                    (name "GND" 
                        (effects 
                            (font 
                                (size 1.27 1.27)))) 
                    (number "1" 
                        (effects 
                            (font 
                                (size 1.27 1.27)))))))
	(symbol "si-simulation-test-board:R_0R_0201" 
            (pin_numbers hide) 
            (pin_names hide) 
            (in_bom yes) 
            (on_board yes) 
            (property "Reference" "R" 
                (id 0) 
                (at 20.32 -5.08 0) 
                (effects 
                    (font 
                        (size 1.27 1.27) 
                        (thickness 0.15)) 
                    (justify left bottom))) 
            (property "Value" "R_0R_0201" 
                (id 1) 
                (at 20.32 -12.7 0) 
                (effects 
                    (font 
                        (size 1.27 1.27) 
                        (thickness 0.15)) 
                    (justify left bottom) hide)) 
            (property "Footprint" "si-simulation-test-board-footprints:R_0201" 
                (id 2) 
                (at 20.32 -15.24 0) 
                (effects 
                    (font 
                        (size 1.27 1.27) 
                        (thickness 0.15)) 
                    (justify left bottom) hide)) 
            (property "Datasheet" "https://www.bourns.com/docs/product-datasheets/cr.pdf" 
                (id 3) 
                (at 20.32 -17.78 0) 
                (effects 
                    (font 
                        (size 1.27 1.27) 
                        (thickness 0.15)) 
                    (justify left bottom) hide)) 
            (property "MPN" "CR0201-FX-0R00GLF" 
                (id 4) 
                (at 20.32 -20.32 0) 
                (effects 
                    (font 
                        (size 1.27 1.27) 
                        (thickness 0.15)) 
                    (justify left bottom) hide)) 
            (property "Manufacturer" "Bourns" 
                (id 5) 
                (at 20.32 -22.86 0) 
                (effects 
                    (font 
                        (size 1.27 1.27) 
                        (thickness 0.15)) 
                    (justify left bottom) hide)) 
            (property "License" "Apache-2.0" 
                (id 6) 
                (at 20.32 -25.4 0) 
                (effects 
                    (font 
                        (size 1.27 1.27) 
                        (thickness 0.15)) 
                    (justify left bottom) hide)) 
            (property "Author" "Antmicro" 
                (id 7) 
                (at 20.32 -27.94 0) 
                (effects 
                    (font 
                        (size 1.27 1.27) 
                        (thickness 0.15)) 
                    (justify left bottom) hide)) 
            (property "Val" "0R" 
                (id 8) 
                (at 20.32 -7.62 0) 
                (effects 
                    (font 
                        (size 1.27 1.27) 
                        (thickness 0.15)) 
                    (justify left bottom))) 
            (property "Tolerance" "1%" 
                (id 9) 
                (at 20.32 -10.16 0) 
                (effects 
                    (font 
                        (size 1.27 1.27)) 
                    (justify left bottom) hide)) 
            (property "ki_description" "SMD Chip Resistor" 
                (id 10) 
                (at 0 0 0) 
                (effects 
                    (font 
                        (size 1.27 1.27)) hide)) 
            (symbol "R_0R_0201_0_1" 
                (rectangle 
                    (start 0.635 0.889) 
                    (end 4.445 -0.889) 
                    (stroke 
                        (width 0.254) 
                        (type default) 
                        (color 0 0 0 0)) 
                    (fill 
                        (type none)))) 
            (symbol "R_0R_0201_1_1" 
                (pin passive line 
                    (at 0 0 0) 
                    (length 0.635) 
                    (name "~" 
                        (effects 
                            (font 
                                (size 1.27 1.27)))) 
                    (number "1" 
                        (effects 
                            (font 
                                (size 1.27 1.27))))) 
                (pin passive line 
                    (at 5.08 0 180) 
                    (length 0.635) 
                    (name "~" 
                        (effects 
                            (font 
                                (size 1.27 1.27)))) 
                    (number "2" 
                        (effects 
                            (font 
                                (size 1.27 1.27)))))))
	(symbol "si-simulation-test-board:R_50R_0402" 
            (pin_numbers hide) 
            (pin_names hide) 
            (in_bom yes) 
            (on_board yes) 
            (property "Reference" "R" 
                (id 0) 
                (at 20.32 -5.08 0) 
                (effects 
                    (font 
                        (size 1.27 1.27) 
                        (thickness 0.15)) 
                    (justify left bottom))) 
            (property "Value" "R_50R_0402" 
                (id 1) 
                (at 20.32 -12.7 0) 
                (effects 
                    (font 
                        (size 1.27 1.27) 
                        (thickness 0.15)) 
                    (justify left bottom) hide)) 
            (property "Footprint" "si-simulation-test-board-footprints:R_0402_1005Metric" 
                (id 2) 
                (at 20.32 -15.24 0) 
                (effects 
                    (font 
                        (size 1.27 1.27) 
                        (thickness 0.15)) 
                    (justify left bottom) hide)) 
            (property "Datasheet" "https://www.bourns.com/docs/product-datasheets/cr.pdf" 
                (id 3) 
                (at 20.32 -17.78 0) 
                (effects 
                    (font 
                        (size 1.27 1.27) 
                        (thickness 0.15)) 
                    (justify left bottom) hide)) 
            (property "MPN" "CR0402-FX-50R0GLF" 
                (id 4) 
                (at 20.32 -20.32 0) 
                (effects 
                    (font 
                        (size 1.27 1.27) 
                        (thickness 0.15)) 
                    (justify left bottom) hide)) 
            (property "Manufacturer" "Bourns" 
                (id 5) 
                (at 20.32 -22.86 0) 
                (effects 
                    (font 
                        (size 1.27 1.27) 
                        (thickness 0.15)) 
                    (justify left bottom) hide)) 
            (property "License" "Apache-2.0" 
                (id 6) 
                (at 20.32 -25.4 0) 
                (effects 
                    (font 
                        (size 1.27 1.27) 
                        (thickness 0.15)) 
                    (justify left bottom) hide)) 
            (property "Author" "Antmicro" 
                (id 7) 
                (at 20.32 -27.94 0) 
                (effects 
                    (font 
                        (size 1.27 1.27) 
                        (thickness 0.15)) 
                    (justify left bottom) hide)) 
            (property "Val" "50R" 
                (id 8) 
                (at 20.32 -7.62 0) 
                (effects 
                    (font 
                        (size 1.27 1.27) 
                        (thickness 0.15)) 
                    (justify left bottom))) 
            (property "Tolerance" "1%" 
                (id 9) 
                (at 20.32 -10.16 0) 
                (effects 
                    (font 
                        (size 1.27 1.27)) 
                    (justify left bottom) hide)) 
            (property "ki_description" "SMD Chip Resistor" 
                (id 10) 
                (at 0 0 0) 
                (effects 
                    (font 
                        (size 1.27 1.27)) hide)) 
            (symbol "R_50R_0402_0_1" 
                (rectangle 
                    (start 0.635 0.889) 
                    (end 4.445 -0.889) 
                    (stroke 
                        (width 0.254) 
                        (type default) 
                        (color 0 0 0 0)) 
                    (fill 
                        (type none)))) 
            (symbol "R_50R_0402_1_1" 
                (pin passive line 
                    (at 0 0 0) 
                    (length 0.635) 
                    (name "~" 
                        (effects 
                            (font 
                                (size 1.27 1.27)))) 
                    (number "1" 
                        (effects 
                            (font 
                                (size 1.27 1.27))))) 
                (pin passive line 
                    (at 5.08 0 180) 
                    (length 0.635) 
                    (name "~" 
                        (effects 
                            (font 
                                (size 1.27 1.27)))) 
                    (number "2" 
                        (effects 
                            (font 
                                (size 1.27 1.27)))))))
)
